# BASEBOARD_FAB2 (Tioga Pass) — schematic netlist excerpt (pin names and nets, part order shuffled) for the footprints in the layout excerpt that follows; sources: Cadence DE-HDL packaged netlist, KiCad conversion of Wiwynn_Tioga_Pass_MB.brd

R25W117  RES  240 1.0% CHIP  pkg 0402  page 151 : A = BMC_ZQ ; B = GND
R3F4  RES  0.0 5% CHIP  pkg 0402  page 104 : A = CLK_156M_OSC_BRD_CPU1_DP ; B = CLK_156M_OSC_CPU1_HFI_DP
C7B14  CAP  2200PF 50V 10% X7R  pkg 0402LF  page 232 : A = VR_COMP_RC_PVPP_DEF ; B = VR_COMP_PVPP_DEF_3

(kicad_pcb
	(version 20260206)
	(generator "pcbnew")
	(generator_version "10.0")
	(general
		(thickness 1.6)
		(legacy_teardrops no)
	)
	(paper "A4")
	(title_block
		(title "Wiwynn_Tioga_Pass_MB.brd")
		(comment 1 "Tioga Pass / footprints 1887-1889 of 4770")
	)
	(layers
		(0 "F.Cu" signal "TOP")
		(4 "In1.Cu" signal "L2GND")
		(6 "In2.Cu" signal "L3")
		(8 "In3.Cu" signal "L4GND")
		(10 "In4.Cu" signal "L5")
		(12 "In5.Cu" signal "L6GND")
		(14 "In6.Cu" signal "L7VCC")
		(16 "In7.Cu" signal "L8VCC")
		(18 "In8.Cu" signal "L9GND")
		(20 "In9.Cu" signal "L10")
		(22 "In10.Cu" signal "L11GND")
		(24 "In11.Cu" signal "L12")
		(26 "In12.Cu" signal "L13GND")
		(2 "B.Cu" signal "BOTTOM")
		(9 "F.Adhes" user "F.Adhesive")
		(11 "B.Adhes" user "B.Adhesive")
		(13 "F.Paste" user "Package Geometry/Pastemask Top")
		(15 "B.Paste" user "Package Geometry/Pastemask Bottom")
		(5 "F.SilkS" user "Ref Des/Silkscreen Top")
		(7 "B.SilkS" user "Ref Des/Silkscreen Bottom")
		(1 "F.Mask" user "Board Geometry/Soldermask Top")
		(3 "B.Mask" user "Board Geometry/Soldermask Bottom")
		(17 "Dwgs.User" user "User.Drawings")
		(19 "Cmts.User" user "User.Comments")
		(21 "Eco1.User" user "User.Eco1")
		(23 "Eco2.User" user "User.Eco2")
		(25 "Edge.Cuts" user "Board Geometry/Outline")
		(27 "Margin" user)
		(31 "F.CrtYd" user "Package Geometry/Place Bound Top")
		(29 "B.CrtYd" user "Package Geometry/Place Bound Bottom")
		(35 "F.Fab" user "Ref Des/Assembly Top")
		(33 "B.Fab" user "Ref Des/Assembly Bottom")
	)
	(footprint ""
		(layer "F.Cu")
		(at 433.3494 -31.7373 180)
		(property "Reference" "R25W117"
			(at -0.8382 -0.67818 180)
			(unlocked yes)
			(layer "F.SilkS")
			(effects
				(font
					(size 0.4064 0.254)
					(thickness 0.1524)
				)
				(justify left)
			)
		)
		(property "Value" ""
			(at 0 0 180)
			(layer "F.Fab")
			(effects
				(font
					(size 1.27 1.27)
				)
			)
		)
		(duplicate_pad_numbers_are_jumpers no)
		(fp_poly
			(pts
				(xy -0.2794 -0.1016) (xy 0.2794 -0.1016) (xy 0.2794 0.9906) (xy -0.2794 0.9906)
			)
			(stroke
				(width 0)
				(type default)
			)
			(fill no)
			(layer "F.CrtYd")
		)
		(fp_line
			(start 0.2794 0.9906)
			(end 0.2794 -0.1016)
			(stroke
				(width 0.1)
				(type default)
			)
			(layer "F.Fab")
		)
		(fp_line
			(start 0.2794 -0.1016)
			(end -0.2794 -0.1016)
			(stroke
				(width 0.1)
				(type default)
			)
			(layer "F.Fab")
		)
		(fp_line
			(start -0.2794 0.9906)
			(end 0.2794 0.9906)
			(stroke
				(width 0.1)
				(type default)
			)
			(layer "F.Fab")
		)
		(fp_line
			(start -0.2794 -0.1016)
			(end -0.2794 0.9906)
			(stroke
				(width 0.1)
				(type default)
			)
			(layer "F.Fab")
		)
		(pad "1" smd rect
			(at 0 0 180)
			(size 0.508 0.508)
			(layers "F.Cu" "F.Mask" "F.Paste")
			(net "BMC_ZQ")
		)
		(pad "2" smd rect
			(at 0 0.889 180)
			(size 0.508 0.508)
			(layers "F.Cu" "F.Mask" "F.Paste")
			(net "GND")
		)
		(zone
			(layer "F.Cu")
			(hatch none 0.5)
			(connect_pads
				(clearance 0)
			)
			(min_thickness 0.25)
			(keepout
				(tracks not_allowed)
				(vias allowed)
				(pads allowed)
				(copperpour not_allowed)
				(footprints allowed)
			)
			(placement
				(enabled no)
				(sheetname "")
			)
			(fill
				(thermal_gap 0.5)
				(thermal_bridge_width 0.5)
				(island_removal_mode 0)
			)
			(polygon
				(pts
					(xy 433.6034 -32.3723) (xy 433.0954 -32.3723) (xy 433.0954 -31.9913) (xy 433.6034 -31.9913)
				)
			)
		)
		(zone
			(layer "F.Cu")
			(hatch none 0.5)
			(connect_pads
				(clearance 0)
			)
			(min_thickness 0.25)
			(keepout
				(tracks allowed)
				(vias not_allowed)
				(pads allowed)
				(copperpour not_allowed)
				(footprints allowed)
			)
			(placement
				(enabled no)
				(sheetname "")
			)
			(fill
				(thermal_gap 0.5)
				(thermal_bridge_width 0.5)
				(island_removal_mode 0)
			)
			(polygon
				(pts
					(xy 433.6034 -31.9913) (xy 433.0954 -31.9913) (xy 433.0954 -32.3723) (xy 433.6034 -32.3723)
				)
			)
		)
	)
	(footprint ""
		(layer "F.Cu")
		(at 154.305 -28.8798 90)
		(property "Reference" "R3F4"
			(at 0 0 90)
			(layer "F.SilkS")
			(hide yes)
			(effects
				(font
					(size 1.27 1.27)
				)
			)
		)
		(property "Value" ""
			(at 0 0 90)
			(layer "F.Fab")
			(effects
				(font
					(size 1.27 1.27)
				)
			)
		)
		(duplicate_pad_numbers_are_jumpers no)
		(fp_poly
			(pts
				(xy -0.2794 -0.1016) (xy 0.2794 -0.1016) (xy 0.2794 0.9906) (xy -0.2794 0.9906)
			)
			(stroke
				(width 0)
				(type default)
			)
			(fill no)
			(layer "F.CrtYd")
		)
		(fp_line
			(start 0.2794 -0.1016)
			(end -0.2794 -0.1016)
			(stroke
				(width 0.1)
				(type default)
			)
			(layer "F.Fab")
		)
		(fp_line
			(start -0.2794 -0.1016)
			(end -0.2794 0.9906)
			(stroke
				(width 0.1)
				(type default)
			)
			(layer "F.Fab")
		)
		(fp_line
			(start 0.2794 0.9906)
			(end 0.2794 -0.1016)
			(stroke
				(width 0.1)
				(type default)
			)
			(layer "F.Fab")
		)
		(fp_line
			(start -0.2794 0.9906)
			(end 0.2794 0.9906)
			(stroke
				(width 0.1)
				(type default)
			)
			(layer "F.Fab")
		)
		(pad "1" smd rect
			(at 0 0 90)
			(size 0.508 0.508)
			(layers "F.Cu" "F.Mask" "F.Paste")
			(net "CLK_156M_OSC_BRD_CPU1_DP")
		)
		(pad "2" smd rect
			(at 0 0.889 90)
			(size 0.508 0.508)
			(layers "F.Cu" "F.Mask" "F.Paste")
			(net "CLK_156M_OSC_CPU1_HFI_DP")
		)
		(zone
			(layer "F.Cu")
			(hatch none 0.5)
			(connect_pads
				(clearance 0)
			)
			(min_thickness 0.25)
			(keepout
				(tracks allowed)
				(vias not_allowed)
				(pads allowed)
				(copperpour not_allowed)
				(footprints allowed)
			)
			(placement
				(enabled no)
				(sheetname "")
			)
			(fill
				(thermal_gap 0.5)
				(thermal_bridge_width 0.5)
				(island_removal_mode 0)
			)
			(polygon
				(pts
					(xy 154.559 -28.6258) (xy 154.559 -29.1338) (xy 154.94 -29.1338) (xy 154.94 -28.6258)
				)
			)
		)
		(zone
			(layer "F.Cu")
			(hatch none 0.5)
			(connect_pads
				(clearance 0)
			)
			(min_thickness 0.25)
			(keepout
				(tracks not_allowed)
				(vias allowed)
				(pads allowed)
				(copperpour not_allowed)
				(footprints allowed)
			)
			(placement
				(enabled no)
				(sheetname "")
			)
			(fill
				(thermal_gap 0.5)
				(thermal_bridge_width 0.5)
				(island_removal_mode 0)
			)
			(polygon
				(pts
					(xy 154.94 -28.6258) (xy 154.94 -29.1338) (xy 154.559 -29.1338) (xy 154.559 -28.6258)
				)
			)
		)
	)
	(footprint ""
		(layer "F.Cu")
		(at 342.4428 -126.746 90)
		(property "Reference" "C7B14"
			(at 0 0 90)
			(layer "F.SilkS")
			(hide yes)
			(effects
				(font
					(size 1.27 1.27)
				)
			)
		)
		(property "Value" ""
			(at 0 0 90)
			(layer "F.Fab")
			(effects
				(font
					(size 1.27 1.27)
				)
			)
		)
		(duplicate_pad_numbers_are_jumpers no)
		(fp_poly
			(pts
				(xy 0.3048 -0.1016) (xy 0.3048 0.9906) (xy -0.3048 0.9906) (xy -0.3048 -0.1016)
			)
			(stroke
				(width 0)
				(type default)
			)
			(fill no)
			(layer "F.CrtYd")
		)
		(fp_line
			(start 0.3048 -0.1016)
			(end -0.3048 -0.1016)
			(stroke
				(width 0.1)
				(type default)
			)
			(layer "F.Fab")
		)
		(fp_line
			(start -0.3048 -0.1016)
			(end -0.3048 0.9906)
			(stroke
				(width 0.1)
				(type default)
			)
			(layer "F.Fab")
		)
		(fp_line
			(start 0.3048 0.9906)
			(end 0.3048 -0.1016)
			(stroke
				(width 0.1)
				(type default)
			)
			(layer "F.Fab")
		)
		(fp_line
			(start -0.3048 0.9906)
			(end 0.3048 0.9906)
			(stroke
				(width 0.1)
				(type default)
			)
			(layer "F.Fab")
		)
		(pad "1" smd rect
			(at 0 0 90)
			(size 0.508 0.508)
			(layers "F.Cu" "F.Mask" "F.Paste")
			(net "VR_COMP_RC_PVPP_DEF")
		)
		(pad "2" smd rect
			(at 0 0.889 90)
			(size 0.508 0.508)
			(layers "F.Cu" "F.Mask" "F.Paste")
			(net "VR_COMP_PVPP_DEF_3")
		)
		(zone
			(layer "F.Cu")
			(hatch none 0.5)
			(connect_pads
				(clearance 0)
			)
			(min_thickness 0.25)
			(keepout
				(tracks allowed)
				(vias not_allowed)
				(pads allowed)
				(copperpour not_allowed)
				(footprints allowed)
			)
			(placement
				(enabled no)
				(sheetname "")
			)
			(fill
				(thermal_gap 0.5)
				(thermal_bridge_width 0.5)
				(island_removal_mode 0)
			)
			(polygon
				(pts
					(xy 342.6968 -126.492) (xy 342.6968 -127) (xy 343.0778 -127) (xy 343.0778 -126.492)
				)
			)
		)
		(zone
			(layer "F.Cu")
			(hatch none 0.5)
			(connect_pads
				(clearance 0)
			)
			(min_thickness 0.25)
			(keepout
				(tracks not_allowed)
				(vias allowed)
				(pads allowed)
				(copperpour not_allowed)
				(footprints allowed)
			)
			(placement
				(enabled no)
				(sheetname "")
			)
			(fill
				(thermal_gap 0.5)
				(thermal_bridge_width 0.5)
				(island_removal_mode 0)
			)
			(polygon
				(pts
					(xy 343.0778 -126.492) (xy 343.0778 -127) (xy 342.6968 -127) (xy 342.6968 -126.492)
				)
			)
		)
	)
)
